(kicad_pcb
	(version 20221018)
	(generator pcbnew)
	(general
    (thickness 1.6)
  )
	(paper "A4")
	(title_block
    (title "NUC Computer Cluster Power Breakout HW")
    (date "2023-10-18")
    (rev "1.4.3")
    (company "Antmicro Ltd.")
		(comment 9 "footprints 171-177 of 234")
	)
	(layers
    (0 "F.Cu" mixed)
    (1 "In1.Cu" power)
    (2 "In2.Cu" mixed)
    (31 "B.Cu" power)
    (32 "B.Adhes" user "B.Adhesive")
    (33 "F.Adhes" user "F.Adhesive")
    (34 "B.Paste" user)
    (35 "F.Paste" user)
    (36 "B.SilkS" user "B.Silkscreen")
    (37 "F.SilkS" user "F.Silkscreen")
    (38 "B.Mask" user)
    (39 "F.Mask" user)
    (40 "Dwgs.User" user "User.Drawings")
    (41 "Cmts.User" user "User.Comments")
    (42 "Eco1.User" user "User.Eco1")
    (43 "Eco2.User" user "User.Eco2")
    (44 "Edge.Cuts" user)
    (45 "Margin" user)
    (46 "B.CrtYd" user "B.Courtyard")
    (47 "F.CrtYd" user "F.Courtyard")
    (48 "B.Fab" user)
    (49 "F.Fab" user)
  )
	(footprint "antmicro-footprints:Conn_Molex_KK_1x4_22-27-2041" (layer "F.Cu")
    (at 169.12 54.01)
    (property "Author" "Antmicro")
    (property "License" "Apache-2.0")
    (property "MPN" "22-27-2041")
    (property "Manufacturer" "Molex")
    (property "Sheetfile" "d1600e-psu-breakout-board.kicad_sch")
    (property "Sheetname" "")
    (property "ki_description" "Rectangular connector (header, female pins)")
    (property "ki_keywords" "VERTICAL, THT, HEADER, CONNECTOR, MALE")
    (attr through_hole)
    (fp_text reference "J14" (at 4.48 4.14) (layer "F.SilkS")
        (effects (font (size 0.7 0.7) (thickness 0.15)) (justify left bottom))
    )
    (fp_text value "Molex_KK_1x4_22-27-2041" (at -0.8 4.6 180) (layer "F.Fab")
        (effects (font (size 0.7 0.7) (thickness 0.15)) (justify left bottom))
    )
    (fp_text user "Author: Antmicro" (at -2.12 6.75) (layer "F.Fab") hide
        (effects (font (size 0.7 0.7) (thickness 0.15)) (justify left bottom))
    )
    (fp_text user "License: Apache-2.0" (at -2.12 7.95) (layer "F.Fab") hide
        (effects (font (size 0.7 0.7) (thickness 0.15)) (justify left bottom))
    )
    (fp_text user "${REFERENCE}" (at -2.12 9.15) (layer "F.Fab") hide
        (effects (font (size 0.7 0.7) (thickness 0.15)) (justify left bottom))
    )
    (fp_line (start -1.39 -3.03) (end -1.39 2.99)
      (stroke (width 0.15) (type solid)) (layer "F.SilkS"))
    (fp_line (start -1.39 2.99) (end 8.99 2.99)
      (stroke (width 0.15) (type solid)) (layer "F.SilkS"))
    (fp_line (start -0.81 -3.03) (end -0.81 -2.43)
      (stroke (width 0.15) (type solid)) (layer "F.SilkS"))
    (fp_line (start -0.81 -2.43) (end 0.79 -2.43)
      (stroke (width 0.15) (type solid)) (layer "F.SilkS"))
    (fp_line (start -0.01 1.99) (end 0.24 1.46)
      (stroke (width 0.15) (type solid)) (layer "F.SilkS"))
    (fp_line (start -0.01 1.99) (end 7.61 1.99)
      (stroke (width 0.15) (type solid)) (layer "F.SilkS"))
    (fp_line (start -0.01 2.99) (end -0.01 1.99)
      (stroke (width 0.15) (type solid)) (layer "F.SilkS"))
    (fp_line (start 0.24 1.46) (end 7.36 1.46)
      (stroke (width 0.15) (type solid)) (layer "F.SilkS"))
    (fp_line (start 0.24 2.99) (end 0.24 1.99)
      (stroke (width 0.15) (type solid)) (layer "F.SilkS"))
    (fp_line (start 0.79 -2.43) (end 0.79 -3.03)
      (stroke (width 0.15) (type solid)) (layer "F.SilkS"))
    (fp_line (start 1.73 -3.03) (end 1.73 -2.43)
      (stroke (width 0.15) (type solid)) (layer "F.SilkS"))
    (fp_line (start 1.73 -2.43) (end 3.33 -2.43)
      (stroke (width 0.15) (type solid)) (layer "F.SilkS"))
    (fp_line (start 3.33 -2.43) (end 3.33 -3.03)
      (stroke (width 0.15) (type solid)) (layer "F.SilkS"))
    (fp_line (start 4.27 -3.03) (end 4.27 -2.43)
      (stroke (width 0.15) (type solid)) (layer "F.SilkS"))
    (fp_line (start 4.27 -2.43) (end 5.87 -2.43)
      (stroke (width 0.15) (type solid)) (layer "F.SilkS"))
    (fp_line (start 5.87 -2.43) (end 5.87 -3.03)
      (stroke (width 0.15) (type solid)) (layer "F.SilkS"))
    (fp_line (start 6.81 -3.03) (end 6.81 -2.43)
      (stroke (width 0.15) (type solid)) (layer "F.SilkS"))
    (fp_line (start 6.81 -2.43) (end 8.41 -2.43)
      (stroke (width 0.15) (type solid)) (layer "F.SilkS"))
    (fp_line (start 7.36 1.46) (end 7.61 1.99)
      (stroke (width 0.15) (type solid)) (layer "F.SilkS"))
    (fp_line (start 7.36 2.99) (end 7.36 1.99)
      (stroke (width 0.15) (type solid)) (layer "F.SilkS"))
    (fp_line (start 7.61 1.99) (end 7.61 2.99)
      (stroke (width 0.15) (type solid)) (layer "F.SilkS"))
    (fp_line (start 8.41 -2.43) (end 8.41 -3.03)
      (stroke (width 0.15) (type solid)) (layer "F.SilkS"))
    (fp_line (start 8.99 -3.03) (end -1.39 -3.03)
      (stroke (width 0.15) (type solid)) (layer "F.SilkS"))
    (fp_line (start 8.99 2.99) (end 8.99 -3.03)
      (stroke (width 0.15) (type solid)) (layer "F.SilkS"))
    (fp_line (start -1.79 -3.38) (end -1.79 3.42)
      (stroke (width 0.05) (type solid)) (layer "F.CrtYd"))
    (fp_line (start -1.79 3.42) (end 9.37 3.42)
      (stroke (width 0.05) (type solid)) (layer "F.CrtYd"))
    (fp_line (start 9.37 -3.38) (end -1.79 -3.38)
      (stroke (width 0.05) (type solid)) (layer "F.CrtYd"))
    (fp_line (start 9.37 3.42) (end 9.37 -3.38)
      (stroke (width 0.05) (type solid)) (layer "F.CrtYd"))
    (fp_line (start -1.29 -2.88) (end -1.29 2.92)
      (stroke (width 0.15) (type solid)) (layer "F.Fab"))
    (fp_line (start -1.29 2.92) (end 8.87 2.92)
      (stroke (width 0.15) (type solid)) (layer "F.Fab"))
    (fp_line (start 8.163 0) (end 8.87 -0.5)
      (stroke (width 0.15) (type solid)) (layer "F.Fab"))
    (fp_line (start 8.87 -2.88) (end -1.29 -2.88)
      (stroke (width 0.15) (type solid)) (layer "F.Fab"))
    (fp_line (start 8.87 0.5) (end 8.163 0)
      (stroke (width 0.15) (type solid)) (layer "F.Fab"))
    (fp_line (start 8.87 2.92) (end 8.87 -2.88)
      (stroke (width 0.15) (type solid)) (layer "F.Fab"))
    (pad "1" thru_hole roundrect (at 0 0) (size 1.74 2.19) (drill 1.19) (layers "*.Cu" "*.Mask") (roundrect_rratio 0.143678)
      (net 11 "VCC12V0") (pintype "passive"))
    (pad "2" thru_hole oval (at 2.54 0) (size 1.74 2.19) (drill 1.19) (layers "*.Cu" "*.Mask")
      (net 4 "GND") (pintype "passive"))
    (pad "3" thru_hole oval (at 5.08 0) (size 1.74 2.19) (drill 1.19) (layers "*.Cu" "*.Mask")
      (net 4 "GND") (pintype "passive"))
    (pad "4" thru_hole oval (at 7.62 0) (size 1.74 2.19) (drill 1.19) (layers "*.Cu" "*.Mask")
      (net 2 "VCC5V0") (pintype "passive"))
  )
	(footprint "antmicro-footprints:TP_SMD_1mm" (layer "F.Cu")
    (at 107.75 79.95)
    (property "Author" "Antmicro")
    (property "License" "Apache-2.0")
    (property "MPN" "")
    (property "Manufacturer" "")
    (property "Sheetfile" "daughterboard-supply.kicad_sch")
    (property "Sheetname" "daughterboard-supply")
    (property "exclude_from_bom" "")
    (property "ki_description" "Test point 1mm SMD")
    (property "ki_keywords" "TESTPOINT")
    (attr exclude_from_pos_files exclude_from_bom)
    (fp_text reference "TP5" (at 0.4 -0.75) (layer "F.SilkS")
        (effects (font (size 0.7 0.7) (thickness 0.15)) (justify left bottom))
    )
    (fp_text value "TP_1mm_SMD" (at 0 1.4) (layer "F.Fab")
        (effects (font (size 0.7 0.7) (thickness 0.15)) (justify left bottom))
    )
    (fp_text user "Author: Antmicro" (at -0.5 4) (layer "F.Fab") hide
        (effects (font (size 0.7 0.7) (thickness 0.15)) (justify left bottom))
    )
    (fp_text user "License: Apache-2.0" (at -0.5 5.2) (layer "F.Fab") hide
        (effects (font (size 0.7 0.7) (thickness 0.15)) (justify left bottom))
    )
    (fp_text user "${REFERENCE}" (at -0.5 2.8) (layer "F.Fab") hide
        (effects (font (size 0.7 0.7) (thickness 0.15)) (justify left bottom))
    )
    (fp_circle (center 0 0) (end 0.6 0)
      (stroke (width 0.05) (type default)) (fill none) (layer "F.CrtYd"))
    (pad "1" smd circle (at 0 0) (size 1 1) (layers "F.Cu" "F.Mask")
      (net 137 "Net-(J9-Pad8)") (pinfunction "1") (pintype "passive"))
  )
	(footprint "antmicro-footprints:R_0402_1005Metric" (layer "F.Cu")
    (at 165.1 100.85 -90)
    (descr "Resistor SMD 0402")
    (tags "resistor SMD 0402")
    (property "Author" "Antmicro")
    (property "License" "Apache-2.0")
    (property "MPN" "CR0402-FX-4701GLF")
    (property "Manufacturer" "Bourns")
    (property "Sheetfile" "ftdi-module.kicad_sch")
    (property "Sheetname" "FTDI")
    (property "Tolerance" "1%")
    (property "Val" "4k7")
    (property "ki_description" "SMD Chip Resistor, 4.7 kohm, ± 1%, 62.5 mW, 0402 [1005 Metric], Thick Film, General Purpose")
    (property "ki_keywords" "0402, SMT, RESISTOR, PASSIVE")
    (attr smd)
    (fp_text reference "R37" (at 1.75 0.55 -90) (layer "F.SilkS")
        (effects (font (size 0.7 0.7) (thickness 0.15)) (justify left bottom))
    )
    (fp_text value "R_4k7_0402" (at -1.011843 1.772047 -90) (layer "F.Fab")
        (effects (font (size 0.7 0.7) (thickness 0.15)) (justify left bottom))
    )
    (fp_text user "${REFERENCE}" (at -0.95 3.168 -90) (layer "F.Fab") hide
        (effects (font (size 0.7 0.7) (thickness 0.15)) (justify left bottom))
    )
    (fp_text user "Author: Antmicro" (at -0.95 4.169 -90) (layer "F.Fab") hide
        (effects (font (size 0.7 0.7) (thickness 0.15)) (justify left bottom))
    )
    (fp_text user "License: Apache-2.0" (at -0.95 5.169 -90) (layer "F.Fab") hide
        (effects (font (size 0.7 0.7) (thickness 0.15)) (justify left bottom))
    )
    (fp_rect (start -0.925 -0.47) (end 0.925 0.47)
      (stroke (width 0.05) (type default)) (fill none) (layer "F.CrtYd"))
    (fp_rect (start -0.5 -0.25) (end 0.5 0.25)
      (stroke (width 0.15) (type solid)) (fill none) (layer "F.Fab"))
    (pad "1" smd roundrect (at -0.48 0 270) (size 0.59 0.64) (layers "F.Cu" "F.Paste" "F.Mask") (roundrect_rratio 0.25)
      (net 18 "SDA") (pintype "passive"))
    (pad "2" smd roundrect (at 0.48 0 270) (size 0.59 0.64) (layers "F.Cu" "F.Paste" "F.Mask") (roundrect_rratio 0.25)
      (net 1 "VCC3V3") (pintype "passive"))
  )
	(footprint "antmicro-footprints:TP_SMD_1mm" (layer "F.Cu")
    (at 184.4 117.3)
    (property "Author" "Antmicro")
    (property "License" "Apache-2.0")
    (property "MPN" "")
    (property "Manufacturer" "")
    (property "Sheetfile" "ftdi-module.kicad_sch")
    (property "Sheetname" "FTDI")
    (property "exclude_from_bom" "")
    (property "ki_description" "Test point 1mm SMD")
    (property "ki_keywords" "TESTPOINT")
    (attr exclude_from_pos_files exclude_from_bom)
    (fp_text reference "TP1" (at 0.9 2.45 180) (layer "F.SilkS")
        (effects (font (size 0.7 0.7) (thickness 0.15)) (justify left bottom))
    )
    (fp_text value "TP_1mm_SMD" (at 0 1.4) (layer "F.Fab")
        (effects (font (size 0.7 0.7) (thickness 0.15)) (justify left bottom))
    )
    (fp_text user "Author: Antmicro" (at -0.5 4) (layer "F.Fab") hide
        (effects (font (size 0.7 0.7) (thickness 0.15)) (justify left bottom))
    )
    (fp_text user "${REFERENCE}" (at -0.5 2.8) (layer "F.Fab") hide
        (effects (font (size 0.7 0.7) (thickness 0.15)) (justify left bottom))
    )
    (fp_text user "License: Apache-2.0" (at -0.5 5.2) (layer "F.Fab") hide
        (effects (font (size 0.7 0.7) (thickness 0.15)) (justify left bottom))
    )
    (fp_circle (center 0 0) (end 0.6 0)
      (stroke (width 0.05) (type default)) (fill none) (layer "F.CrtYd"))
    (pad "1" smd circle (at 0 0) (size 1 1) (layers "F.Cu" "F.Mask")
      (net 113 "Net-(U1-CC_{1})") (pinfunction "1") (pintype "passive"))
  )
	(footprint "antmicro-footprints:D_SOD-323" (layer "F.Cu")
    (at 118.1 91.4 -90)
    (property "Author" "Antmicro")
    (property "License" "Apache-2.0")
    (property "MPN" "BZT52B15SV-T")
    (property "Manufacturer" "Rectron")
    (property "Sheetfile" "power-switch.kicad_sch")
    (property "Sheetname" "Power switch 1")
    (property "ki_description" "Zener Single Diode, AEC-Q101, 15 V, 500 mW, SOD-323, 2 Pins, 150 °C, Surface Mount")
    (property "ki_keywords" "SMT, DIODE, SEMICONDUCTOR, ZENER")
    (attr smd)
    (fp_text reference "D15" (at 2.7 2.6) (layer "F.SilkS")
        (effects (font (size 0.7 0.7) (thickness 0.15)) (justify left bottom))
    )
    (fp_text value "BZT52B15SV-T" (at 0 1.841 -90) (layer "F.Fab")
        (effects (font (size 0.7 0.7) (thickness 0.15)) (justify left bottom))
    )
    (fp_text user "${REFERENCE}" (at -1.4 5.041 -90) (layer "F.Fab") hide
        (effects (font (size 0.7 0.7) (thickness 0.15)) (justify left bottom))
    )
    (fp_text user "Author: Antmicro" (at -1.4 6.241 -90) (layer "F.Fab") hide
        (effects (font (size 0.7 0.7) (thickness 0.15)) (justify left bottom))
    )
    (fp_text user "License: Apache-2.0" (at -1.4 3.841 -90) (layer "F.Fab") hide
        (effects (font (size 0.7 0.7) (thickness 0.15)) (justify left bottom))
    )
    (fp_line (start -0.949 -0.749) (end -0.949 -0.499)
      (stroke (width 0.15) (type solid)) (layer "F.SilkS"))
    (fp_line (start -0.949 0.501) (end -0.949 0.751)
      (stroke (width 0.15) (type solid)) (layer "F.SilkS"))
    (fp_line (start -0.6 -0.499) (end -0.6 0.499)
      (stroke (width 0.15) (type solid)) (layer "F.SilkS"))
    (fp_line (start -0.577 -0.749) (end -0.949 -0.749)
      (stroke (width 0.15) (type solid)) (layer "F.SilkS"))
    (fp_line (start -0.577 0.751) (end -0.949 0.751)
      (stroke (width 0.15) (type solid)) (layer "F.SilkS"))
    (fp_line (start 0.625 -0.736) (end 0.949 -0.736)
      (stroke (width 0.15) (type solid)) (layer "F.SilkS"))
    (fp_line (start 0.949 -0.736) (end 0.949 -0.499)
      (stroke (width 0.15) (type solid)) (layer "F.SilkS"))
    (fp_line (start 0.95 0.501) (end 0.95 0.751)
      (stroke (width 0.15) (type solid)) (layer "F.SilkS"))
    (fp_line (start 0.95 0.751) (end 0.649 0.751)
      (stroke (width 0.15) (type solid)) (layer "F.SilkS"))
    (fp_rect (start -1.6 -0.925) (end 1.6 0.925)
      (stroke (width 0.05) (type solid)) (fill none) (layer "F.CrtYd"))
    (fp_line (start -0.902 0.699) (end -0.902 -0.699)
      (stroke (width 0.15) (type solid)) (layer "F.Fab"))
    (fp_line (start -0.902 0.699) (end 0.9 0.699)
      (stroke (width 0.15) (type solid)) (layer "F.Fab"))
    (fp_line (start 0.9 -0.699) (end -0.902 -0.699)
      (stroke (width 0.15) (type solid)) (layer "F.Fab"))
    (fp_line (start 0.9 -0.699) (end 0.9 0.699)
      (stroke (width 0.15) (type solid)) (layer "F.Fab"))
    (pad "1" smd rect (at -1.125 0.001 270) (size 0.8 0.8) (layers "F.Cu" "F.Paste" "F.Mask")
      (net 11 "VCC12V0") (pinfunction "C") (pintype "passive"))
    (pad "2" smd rect (at 1.124 0.001 270) (size 0.8 0.8) (layers "F.Cu" "F.Paste" "F.Mask")
      (net 83 "Net-(D15-A)") (pinfunction "A") (pintype "passive"))
  )
	(footprint "antmicro-footprints:R_0402_1005Metric" (layer "F.Cu")
    (at 145.9 89.5 180)
    (descr "Resistor SMD 0402")
    (tags "resistor SMD 0402")
    (property "Author" "Antmicro")
    (property "DNP" "DNP")
    (property "License" "Apache-2.0")
    (property "MPN" "CR0402-FX-1002GLF")
    (property "Manufacturer" "Bourns")
    (property "Sheetfile" "power-switch.kicad_sch")
    (property "Sheetname" "Power switch 3")
    (property "Tolerance" "1%")
    (property "Val" "10k")
    (property "dnp" "")
    (property "exclude_from_bom" "")
    (property "ki_description" "SMD Chip Resistor, 10 kohm, ± 1%, 62.5 mW, 0402 [1005 Metric], Thick Film, General Purpose")
    (property "ki_keywords" "0402, SMT, RESISTOR, PASSIVE")
    (attr smd exclude_from_bom)
    (fp_text reference "R50" (at 2 -0.1) (layer "F.SilkS")
        (effects (font (size 0.7 0.7) (thickness 0.15)))
    )
    (fp_text value "R_10k_0402" (at 0 1.17) (layer "F.Fab") hide
        (effects (font (size 1 1) (thickness 0.15)))
    )
    (fp_text user "Author: Antmicro" (at -0.95 4.169 180) (layer "F.Fab") hide
        (effects (font (size 0.7 0.7) (thickness 0.15)) (justify left bottom))
    )
    (fp_text user "${REFERENCE}" (at 0 0) (layer "F.Fab")
        (effects (font (size 0.25 0.25) (thickness 0.04)))
    )
    (fp_text user "License: Apache-2.0" (at -0.95 5.169 180) (layer "F.Fab") hide
        (effects (font (size 0.7 0.7) (thickness 0.15)) (justify left bottom))
    )
    (fp_rect (start -0.925 -0.47) (end 0.925 0.47)
      (stroke (width 0.05) (type default)) (fill none) (layer "F.CrtYd"))
    (fp_rect (start -0.5 -0.25) (end 0.5 0.25)
      (stroke (width 0.15) (type solid)) (fill none) (layer "F.Fab"))
    (pad "1" smd roundrect (at -0.48 0 180) (size 0.59 0.64) (layers "F.Cu" "F.Paste" "F.Mask") (roundrect_rratio 0.25)
      (net 30 "/Power Cycling & Current Measurement/PC_3") (pintype "passive"))
    (pad "2" smd roundrect (at 0.48 0 180) (size 0.59 0.64) (layers "F.Cu" "F.Paste" "F.Mask") (roundrect_rratio 0.25)
      (net 4 "GND") (pintype "passive"))
  )
	(footprint "antmicro-footprints:C_0402_1005Metric" (layer "F.Cu")
    (at 170.1 125.4 90)
    (descr "Capacitor SMD 0402")
    (tags "capacitor SMD 0402")
    (property "Author" "Antmicro")
    (property "Dielectric" "")
    (property "License" "Apache-2.0")
    (property "MPN" "CL05C180JB51PNC")
    (property "Manufacturer" "Samsung Electro-Mechanics")
    (property "Sheetfile" "ftdi-module.kicad_sch")
    (property "Sheetname" "FTDI")
    (property "Val" "18p")
    (property "Voltage" "")
    (property "ki_description" "SMD Multilayer Ceramic Capacitor, 18 pF, 50 V, 0402 [1005 Metric], ± 5%, C0G / NP0, MC")
    (property "ki_keywords" "0402, SMT, CAPACITOR, PASSIVE")
    (attr smd)
    (fp_text reference "C2" (at -0.65 1.5 90) (layer "F.SilkS")
        (effects (font (size 0.7 0.7) (thickness 0.15)) (justify left bottom))
    )
    (fp_text value "C_18p_0402" (at -1.022927 2.155213 90) (layer "F.Fab")
        (effects (font (size 0.7 0.7) (thickness 0.15)) (justify left bottom))
    )
    (fp_text user "Author: Antmicro" (at -0.939 3.399 90) (layer "F.Fab") hide
        (effects (font (size 0.7 0.7) (thickness 0.15)) (justify left bottom))
    )
    (fp_text user "${REFERENCE}" (at -0.939 4.599 90) (layer "F.Fab") hide
        (effects (font (size 0.7 0.7) (thickness 0.15)) (justify left bottom))
    )
    (fp_text user "License: Apache-2.0" (at -0.939 5.799 90) (layer "F.Fab") hide
        (effects (font (size 0.7 0.7) (thickness 0.15)) (justify left bottom))
    )
    (fp_rect (start -0.925 -0.47) (end 0.925 0.47)
      (stroke (width 0.05) (type default)) (fill none) (layer "F.CrtYd"))
    (fp_line (start -0.494 -0.25) (end 0.504 -0.25)
      (stroke (width 0.15) (type solid)) (layer "F.Fab"))
    (fp_line (start -0.494 0.248) (end -0.494 -0.25)
      (stroke (width 0.15) (type solid)) (layer "F.Fab"))
    (fp_line (start 0.504 -0.25) (end 0.504 0.248)
      (stroke (width 0.15) (type solid)) (layer "F.Fab"))
    (fp_line (start 0.504 0.248) (end -0.494 0.248)
      (stroke (width 0.15) (type solid)) (layer "F.Fab"))
    (pad "1" smd roundrect (at -0.48 0 90) (size 0.59 0.64) (layers "F.Cu" "F.Paste" "F.Mask") (roundrect_rratio 0.25)
      (net 77 "GNDD") (pintype "passive"))
    (pad "2" smd roundrect (at 0.48 0 90) (size 0.59 0.64) (layers "F.Cu" "F.Paste" "F.Mask") (roundrect_rratio 0.25)
      (net 5 "/FTDI/OSCI") (pintype "passive"))
  )
)
